# BASEBOARD_FAB2 (Tioga Pass) — schematic netlist excerpt (pin names and nets, part order shuffled) for the footprints in the layout excerpt that follows; sources: Cadence DE-HDL packaged netlist, KiCad conversion of Wiwynn_Tioga_Pass_MB.brd

R8F12  RES  33.2 1% CHIP  pkg 0402  page 162 : A = SPI_BMC_BT_DI ; B = SPI_BMC_BT_DI_R

U6W2  TCA9517DGKR-GP  pkg DISCRET-G8  page 247
  VCCA  = P3V3_STBY
  SCLA  = SMB_PMBUS_BMC_STBY_LVC3_SCL_R1
  SDAA  = SMB_PMBUS_BMC_STBY_LVC3_SDA_R1
  GND  = GND
  EN  = HSC_SMBUS_SWITCH_EN
  SDAB  = SMB_BMC_PMBUS_STBY_LVC3_SDA
  SCLB  = SMB_BMC_PMBUS_STBY_LVC3_SCL
  VCCB  = P3V3_STBY

(kicad_pcb
	(version 20260206)
	(generator "pcbnew")
	(generator_version "10.0")
	(general
		(thickness 1.6)
		(legacy_teardrops no)
	)
	(paper "A4")
	(title_block
		(title "Wiwynn_Tioga_Pass_MB.brd")
		(comment 1 "Tioga Pass / footprints 2853-2854 of 4770")
	)
	(layers
		(0 "F.Cu" signal "TOP")
		(4 "In1.Cu" signal "L2GND")
		(6 "In2.Cu" signal "L3")
		(8 "In3.Cu" signal "L4GND")
		(10 "In4.Cu" signal "L5")
		(12 "In5.Cu" signal "L6GND")
		(14 "In6.Cu" signal "L7VCC")
		(16 "In7.Cu" signal "L8VCC")
		(18 "In8.Cu" signal "L9GND")
		(20 "In9.Cu" signal "L10")
		(22 "In10.Cu" signal "L11GND")
		(24 "In11.Cu" signal "L12")
		(26 "In12.Cu" signal "L13GND")
		(2 "B.Cu" signal "BOTTOM")
		(9 "F.Adhes" user "F.Adhesive")
		(11 "B.Adhes" user "B.Adhesive")
		(13 "F.Paste" user "Package Geometry/Pastemask Top")
		(15 "B.Paste" user "Package Geometry/Pastemask Bottom")
		(5 "F.SilkS" user "Ref Des/Silkscreen Top")
		(7 "B.SilkS" user "Ref Des/Silkscreen Bottom")
		(1 "F.Mask" user "Board Geometry/Soldermask Top")
		(3 "B.Mask" user "Board Geometry/Soldermask Bottom")
		(17 "Dwgs.User" user "User.Drawings")
		(19 "Cmts.User" user "User.Comments")
		(21 "Eco1.User" user "User.Eco1")
		(23 "Eco2.User" user "User.Eco2")
		(25 "Edge.Cuts" user "Board Geometry/Outline")
		(27 "Margin" user)
		(31 "F.CrtYd" user "Package Geometry/Place Bound Top")
		(29 "B.CrtYd" user "Package Geometry/Place Bound Bottom")
		(35 "F.Fab" user "Ref Des/Assembly Top")
		(33 "B.Fab" user "Ref Des/Assembly Bottom")
	)
	(footprint ""
		(layer "B.Cu")
		(at 401.55114 -76.66736 -90)
		(property "Reference" "U6W2"
			(at 0 0 90)
			(layer "B.SilkS")
			(hide yes)
			(effects
				(font
					(size 1.27 1.27)
				)
				(justify mirror)
			)
		)
		(property "Value" "*"
			(at 0.1143 -9.3091 270)
			(unlocked yes)
			(layer "B.Fab")
			(hide yes)
			(effects
				(font
					(size 1.27 1.016)
					(thickness 0.1524)
				)
				(justify mirror)
			)
		)
		(property "Device Type" "TCA9517DGKR-GP_DISCRET-G8-TCA9A"
			(at 0.1143 -10.9093 270)
			(unlocked yes)
			(layer "B.Fab")
			(hide yes)
			(effects
				(font
					(size 1.27 1.016)
					(thickness 0.1524)
				)
				(justify mirror)
			)
		)
		(duplicate_pad_numbers_are_jumpers no)
		(fp_line
			(start 1.778 1.0922)
			(end 1.778 3.048)
			(stroke
				(width 0.508)
				(type default)
			)
			(layer "B.SilkS")
		)
		(fp_line
			(start -1.0795 1.016)
			(end -1.0795 -1.016)
			(stroke
				(width 0.1524)
				(type default)
			)
			(layer "B.SilkS")
		)
		(fp_line
			(start 1.9558 1.016)
			(end -1.0795 1.016)
			(stroke
				(width 0.1524)
				(type default)
			)
			(layer "B.SilkS")
		)
		(fp_line
			(start 1.4478 -0.0381)
			(end 1.9558 0.4699)
			(stroke
				(width 0.1524)
				(type default)
			)
			(layer "B.SilkS")
		)
		(fp_line
			(start 1.9558 -0.5461)
			(end 1.4478 -0.0381)
			(stroke
				(width 0.1524)
				(type default)
			)
			(layer "B.SilkS")
		)
		(fp_line
			(start -1.0795 -1.016)
			(end 1.9558 -1.016)
			(stroke
				(width 0.1524)
				(type default)
			)
			(layer "B.SilkS")
		)
		(fp_line
			(start 1.9558 -1.016)
			(end 1.9558 1.016)
			(stroke
				(width 0.1524)
				(type default)
			)
			(layer "B.SilkS")
		)
		(fp_poly
			(pts
				(xy 1.1557 -1.016) (xy 1.1557 1.016) (xy -1.1557 1.016) (xy -1.1557 -1.016)
			)
			(stroke
				(width 0)
				(type default)
			)
			(fill yes)
			(layer "B.SilkS")
		)
		(fp_rect
			(start 1.4986 2.4511)
			(end -1.4986 -2.4511)
			(stroke
				(width 0)
				(type default)
			)
			(fill no)
			(layer "B.CrtYd")
		)
		(fp_poly
			(pts
				(xy 2.032 3.302) (xy 2.032 -3.302) (xy -2.032 -3.302) (xy -2.032 -2.1209) (xy -1.4986 -2.1209) (xy -1.4986 -2.4511)
				(xy 1.4986 -2.4511) (xy 1.4986 2.4511) (xy -1.4986 2.4511) (xy -1.4986 -2.1082) (xy -2.032 -2.1082)
				(xy -2.032 3.302)
			)
			(stroke
				(width 0)
				(type default)
			)
			(fill no)
			(layer "B.CrtYd")
		)
		(fp_rect
			(start 2.032 3.302)
			(end -2.032 -3.302)
			(stroke
				(width 0)
				(type default)
			)
			(fill no)
			(layer "B.Fab")
		)
		(pad "1" smd rect
			(at 0.97536 2.05486 90)
			(size 0.3556 1.524)
			(layers "B.Cu" "B.Mask" "B.Paste")
			(net "P3V3_STBY")
		)
		(pad "2" smd rect
			(at 0.32512 2.05486 90)
			(size 0.3556 1.524)
			(layers "B.Cu" "B.Mask" "B.Paste")
			(net "SMB_PMBUS_BMC_STBY_LVC3_SCL_R1")
		)
		(pad "3" smd rect
			(at -0.32512 2.05486 90)
			(size 0.3556 1.524)
			(layers "B.Cu" "B.Mask" "B.Paste")
			(net "SMB_PMBUS_BMC_STBY_LVC3_SDA_R1")
		)
		(pad "4" smd rect
			(at -0.97536 2.05486 90)
			(size 0.3556 1.524)
			(layers "B.Cu" "B.Mask" "B.Paste")
			(net "GND")
		)
		(pad "5" smd rect
			(at -0.97536 -2.05486 90)
			(size 0.3556 1.524)
			(layers "B.Cu" "B.Mask" "B.Paste")
			(net "HSC_SMBUS_SWITCH_EN")
		)
		(pad "6" smd rect
			(at -0.32512 -2.05486 90)
			(size 0.3556 1.524)
			(layers "B.Cu" "B.Mask" "B.Paste")
			(net "SMB_BMC_PMBUS_STBY_LVC3_SDA")
		)
		(pad "7" smd rect
			(at 0.32512 -2.05486 90)
			(size 0.3556 1.524)
			(layers "B.Cu" "B.Mask" "B.Paste")
			(net "SMB_BMC_PMBUS_STBY_LVC3_SCL")
		)
		(pad "8" smd rect
			(at 0.97536 -2.05486 90)
			(size 0.3556 1.524)
			(layers "B.Cu" "B.Mask" "B.Paste")
			(net "P3V3_STBY")
		)
	)
	(footprint ""
		(layer "B.Cu")
		(at 367.637314 -35.364166 180)
		(property "Reference" "R8F12"
			(at 0 0 0)
			(layer "B.SilkS")
			(hide yes)
			(effects
				(font
					(size 1.27 1.27)
				)
				(justify mirror)
			)
		)
		(property "Value" ""
			(at 0 0 0)
			(layer "B.Fab")
			(effects
				(font
					(size 1.27 1.27)
				)
				(justify mirror)
			)
		)
		(duplicate_pad_numbers_are_jumpers no)
		(fp_poly
			(pts
				(xy 0.2794 -0.1016) (xy -0.2794 -0.1016) (xy -0.2794 0.9906) (xy 0.2794 0.9906)
			)
			(stroke
				(width 0)
				(type default)
			)
			(fill no)
			(layer "B.CrtYd")
		)
		(fp_line
			(start 0.2794 0.9906)
			(end -0.2794 0.9906)
			(stroke
				(width 0.1)
				(type default)
			)
			(layer "B.Fab")
		)
		(fp_line
			(start 0.2794 -0.1016)
			(end 0.2794 0.9906)
			(stroke
				(width 0.1)
				(type default)
			)
			(layer "B.Fab")
		)
		(fp_line
			(start -0.2794 0.9906)
			(end -0.2794 -0.1016)
			(stroke
				(width 0.1)
				(type default)
			)
			(layer "B.Fab")
		)
		(fp_line
			(start -0.2794 -0.1016)
			(end 0.2794 -0.1016)
			(stroke
				(width 0.1)
				(type default)
			)
			(layer "B.Fab")
		)
		(pad "1" smd rect
			(at 0 0)
			(size 0.508 0.508)
			(layers "B.Cu" "B.Mask" "B.Paste")
			(net "SPI_BMC_BT_DI")
		)
		(pad "2" smd rect
			(at 0 0.889)
			(size 0.508 0.508)
			(layers "B.Cu" "B.Mask" "B.Paste")
			(net "SPI_BMC_BT_DI_R")
		)
		(zone
			(layer "B.Cu")
			(hatch none 0.5)
			(connect_pads
				(clearance 0)
			)
			(min_thickness 0.25)
			(keepout
				(tracks not_allowed)
				(vias allowed)
				(pads allowed)
				(copperpour not_allowed)
				(footprints allowed)
			)
			(placement
				(enabled no)
				(sheetname "")
			)
			(fill
				(thermal_gap 0.5)
				(thermal_bridge_width 0.5)
				(island_removal_mode 0)
			)
			(polygon
				(pts
					(xy 367.383314 -35.999166) (xy 367.891314 -35.999166) (xy 367.891314 -35.618166) (xy 367.383314 -35.618166)
				)
			)
		)
		(zone
			(layer "B.Cu")
			(hatch none 0.5)
			(connect_pads
				(clearance 0)
			)
			(min_thickness 0.25)
			(keepout
				(tracks allowed)
				(vias not_allowed)
				(pads allowed)
				(copperpour not_allowed)
				(footprints allowed)
			)
			(placement
				(enabled no)
				(sheetname "")
			)
			(fill
				(thermal_gap 0.5)
				(thermal_bridge_width 0.5)
				(island_removal_mode 0)
			)
			(polygon
				(pts
					(xy 367.383314 -35.618166) (xy 367.891314 -35.618166) (xy 367.891314 -35.999166) (xy 367.383314 -35.999166)
				)
			)
		)
	)
)
